# S9S_MB_2U (Grand Teton) — schematic netlist excerpt (pin names and nets, part order shuffled) for the footprints in the layout excerpt that follows; sources: Cadence DE-HDL packaged netlist, KiCad conversion of 03242023_DA0F0TMBIJ0_F0T_Motherboard_J_brd_V01_OCP.brd

C167  Q_CAP_DIFFBUS  DIFF BUS_0.22UF 6.3V 20% X6S  pkg C0201  page 178 : \1\ = DMI_CPU0_PCH_RX_C_DN<1> ; \2\ = DMI_CPU0_PCH_RX_DN<1>
C357  Q_CAP  47UF 4V 20% X6S  pkg C0805  page 75 : A = PVCCIN_CPU0 ; B = GND
PC418  Q_CAPP  330UF 2.5V +10/-35% SPCAP  pkg SMLF  page 289 : A = PVCCFA_EHV_FIVRA_CPU1 ; B = GND
C49  Q_CAP  10UF 16V 10% X6S  pkg C0805  page 97 : A = P12V_S3_AUX_CPU0_NVDIMM ; B = GND

(kicad_pcb
	(version 20260206)
	(generator "pcbnew")
	(generator_version "10.0")
	(general
		(thickness 1.6)
		(legacy_teardrops no)
	)
	(paper "A4")
	(title_block
		(title "03242023_DA0F0TMBIJ0_F0T_Motherboard_J_brd_V01_OCP.brd")
		(comment 1 "Grand Teton / footprints 5857-5860 of 6105")
	)
	(layers
		(0 "F.Cu" signal "TOP")
		(4 "In1.Cu" signal "GND")
		(6 "In2.Cu" signal "IN1")
		(8 "In3.Cu" signal "GND1")
		(10 "In4.Cu" signal "IN2")
		(12 "In5.Cu" signal "GND2")
		(14 "In6.Cu" signal "IN3")
		(16 "In7.Cu" signal "GND3")
		(18 "In8.Cu" signal "VCC")
		(20 "In9.Cu" signal "VCC1")
		(22 "In10.Cu" signal "GND4")
		(24 "In11.Cu" signal "IN4")
		(26 "In12.Cu" signal "GND5")
		(28 "In13.Cu" signal "IN5")
		(30 "In14.Cu" signal "GND6")
		(32 "In15.Cu" signal "IN6")
		(34 "In16.Cu" signal "GND7")
		(2 "B.Cu" signal "BOTTOM")
		(9 "F.Adhes" user "F.Adhesive")
		(11 "B.Adhes" user "B.Adhesive")
		(13 "F.Paste" user "Package Geometry/Pastemask Top")
		(15 "B.Paste" user "Package Geometry/Pastemask Bottom")
		(5 "F.SilkS" user "Ref Des/Silkscreen Top")
		(7 "B.SilkS" user "Ref Des/Silkscreen Bottom")
		(1 "F.Mask" user "Board Geometry/Soldermask Top")
		(3 "B.Mask" user "Board Geometry/Soldermask Bottom")
		(17 "Dwgs.User" user "User.Drawings")
		(19 "Cmts.User" user "User.Comments")
		(21 "Eco1.User" user "User.Eco1")
		(23 "Eco2.User" user "User.Eco2")
		(25 "Edge.Cuts" user "Board Geometry/Outline")
		(27 "Margin" user)
		(31 "F.CrtYd" user "Package Geometry/Place Bound Top")
		(29 "B.CrtYd" user "Package Geometry/Place Bound Bottom")
		(35 "F.Fab" user "Ref Des/Assembly Top")
		(33 "B.Fab" user "Ref Des/Assembly Bottom")
	)
	(footprint ""
		(layer "B.Cu")
		(at 452.028814 -321.549776 -90)
		(property "Reference" "C49"
			(at 0 0 90)
			(layer "B.SilkS")
			(hide yes)
			(effects
				(font
					(size 1.27 1.27)
				)
				(justify mirror)
			)
		)
		(property "Value" ""
			(at 0 0 90)
			(layer "B.Fab")
			(effects
				(font
					(size 1.27 1.27)
				)
				(justify mirror)
			)
		)
		(duplicate_pad_numbers_are_jumpers no)
		(fp_line
			(start -1.524 0.762)
			(end 1.524 0.762)
			(stroke
				(width 0.1524)
				(type default)
			)
			(layer "B.SilkS")
		)
		(fp_line
			(start 1.524 0.762)
			(end 1.524 -0.762)
			(stroke
				(width 0.1524)
				(type default)
			)
			(layer "B.SilkS")
		)
		(fp_line
			(start -1.524 -0.762)
			(end -1.524 0.762)
			(stroke
				(width 0.1524)
				(type default)
			)
			(layer "B.SilkS")
		)
		(fp_line
			(start 1.524 -0.762)
			(end -1.524 -0.762)
			(stroke
				(width 0.1524)
				(type default)
			)
			(layer "B.SilkS")
		)
		(fp_line
			(start -1.1049 0.724916)
			(end -1.1049 -0.724916)
			(stroke
				(width 0.1)
				(type default)
			)
			(layer "B.Fab")
		)
		(fp_line
			(start 1.1049 0.724916)
			(end -1.1049 0.724916)
			(stroke
				(width 0.1)
				(type default)
			)
			(layer "B.Fab")
		)
		(fp_line
			(start -1.1049 -0.724916)
			(end 1.1049 -0.724916)
			(stroke
				(width 0.1)
				(type default)
			)
			(layer "B.Fab")
		)
		(fp_line
			(start 1.1049 -0.724916)
			(end 1.1049 0.724916)
			(stroke
				(width 0.1)
				(type default)
			)
			(layer "B.Fab")
		)
		(pad "1" smd rect
			(at 0.889 0 270)
			(size 1.016 1.27)
			(layers "B.Cu" "B.Mask" "B.Paste")
			(net "P12V_S3_AUX_CPU0_NVDIMM")
		)
		(pad "2" smd rect
			(at -0.889 0 270)
			(size 1.016 1.27)
			(layers "B.Cu" "B.Mask" "B.Paste")
			(net "GND")
		)
	)
	(footprint ""
		(layer "B.Cu")
		(at 340.35746 -66.425064 90)
		(property "Reference" "C167"
			(at 0 0 90)
			(layer "B.SilkS")
			(hide yes)
			(effects
				(font
					(size 1.27 1.27)
				)
				(justify mirror)
			)
		)
		(property "Value" ""
			(at 0 0 90)
			(layer "B.Fab")
			(effects
				(font
					(size 1.27 1.27)
				)
				(justify mirror)
			)
		)
		(duplicate_pad_numbers_are_jumpers no)
		(fp_line
			(start 0.299974 -0.150114)
			(end -0.299974 -0.150114)
			(stroke
				(width 0.1)
				(type default)
			)
			(layer "B.Fab")
		)
		(fp_line
			(start -0.299974 -0.150114)
			(end -0.299974 0.150114)
			(stroke
				(width 0.1)
				(type default)
			)
			(layer "B.Fab")
		)
		(fp_line
			(start 0.299974 0.150114)
			(end 0.299974 -0.150114)
			(stroke
				(width 0.1)
				(type default)
			)
			(layer "B.Fab")
		)
		(fp_line
			(start -0.299974 0.150114)
			(end 0.299974 0.150114)
			(stroke
				(width 0.1)
				(type default)
			)
			(layer "B.Fab")
		)
		(pad "1" smd rect
			(at 0.2667 0 270)
			(size 0.3048 0.381)
			(layers "B.Cu" "B.Mask" "B.Paste")
			(net "DMI_CPU0_PCH_RX_C_DN<1>")
		)
		(pad "2" smd rect
			(at -0.2667 0 270)
			(size 0.3048 0.381)
			(layers "B.Cu" "B.Mask" "B.Paste")
			(net "DMI_CPU0_PCH_RX_DN<1>")
		)
	)
	(footprint ""
		(layer "B.Cu")
		(at 171.985178 -346.586302 -90)
		(property "Reference" "PC418"
			(at 0 0 90)
			(layer "B.SilkS")
			(hide yes)
			(effects
				(font
					(size 1.27 1.27)
				)
				(justify mirror)
			)
		)
		(property "Value" ""
			(at 0 0 90)
			(layer "B.Fab")
			(effects
				(font
					(size 1.27 1.27)
				)
				(justify mirror)
			)
		)
		(duplicate_pad_numbers_are_jumpers no)
		(fp_line
			(start -4.533392 2.249932)
			(end 4.533392 2.249932)
			(stroke
				(width 0.1524)
				(type default)
			)
			(layer "B.SilkS")
		)
		(fp_line
			(start 4.533392 2.249932)
			(end 4.533392 -2.249932)
			(stroke
				(width 0.1524)
				(type default)
			)
			(layer "B.SilkS")
		)
		(fp_line
			(start -4.533392 -2.249932)
			(end -4.533392 2.249932)
			(stroke
				(width 0.1524)
				(type default)
			)
			(layer "B.SilkS")
		)
		(fp_line
			(start 4.533392 -2.249932)
			(end -4.533392 -2.249932)
			(stroke
				(width 0.1524)
				(type default)
			)
			(layer "B.SilkS")
		)
		(fp_poly
			(pts
				(xy 4.533392 -2.326132) (xy 5.39242 -2.326132) (xy 5.39242 2.326132) (xy 4.533392 2.326132)
			)
			(stroke
				(width 0)
				(type default)
			)
			(fill yes)
			(layer "B.SilkS")
		)
		(fp_line
			(start -3.750056 2.249932)
			(end 3.750056 2.249932)
			(stroke
				(width 0.1)
				(type default)
			)
			(layer "B.Fab")
		)
		(fp_line
			(start 3.750056 2.249932)
			(end 3.750056 -2.249932)
			(stroke
				(width 0.1)
				(type default)
			)
			(layer "B.Fab")
		)
		(fp_line
			(start -3.750056 -2.249932)
			(end -3.750056 2.249932)
			(stroke
				(width 0.1)
				(type default)
			)
			(layer "B.Fab")
		)
		(fp_line
			(start 3.750056 -2.249932)
			(end -3.750056 -2.249932)
			(stroke
				(width 0.1)
				(type default)
			)
			(layer "B.Fab")
		)
		(fp_text user "+"
			(at 6.322314 0.786384 180)
			(unlocked yes)
			(layer "B.SilkS")
			(effects
				(font
					(size 1.905 1.4224)
					(thickness 0.1524)
				)
				(justify left mirror)
			)
		)
		(fp_text user "-"
			(at -4.8514 -0.14605 270)
			(unlocked yes)
			(layer "B.SilkS")
			(effects
				(font
					(size 1.905 1.4224)
					(thickness 0.1524)
				)
				(justify left mirror)
			)
		)
		(fp_text user "+"
			(at 6.322314 0.786384 180)
			(unlocked yes)
			(layer "B.Fab")
			(effects
				(font
					(size 1.905 1.4224)
					(thickness 0.1524)
				)
				(justify left mirror)
			)
		)
		(fp_text user "-"
			(at -4.8514 -0.14605 270)
			(unlocked yes)
			(layer "B.Fab")
			(effects
				(font
					(size 1.905 1.4224)
					(thickness 0.1524)
				)
				(justify left mirror)
			)
		)
		(pad "1" smd rect
			(at 3.199892 0 90)
			(size 2.413 2.8194)
			(layers "B.Cu" "B.Mask" "B.Paste")
			(net "PVCCFA_EHV_FIVRA_CPU1")
		)
		(pad "2" smd rect
			(at -3.199892 0 90)
			(size 2.413 2.8194)
			(layers "B.Cu" "B.Mask" "B.Paste")
			(net "GND")
		)
	)
	(footprint ""
		(layer "B.Cu")
		(at 353.619308 -248.498106 -90)
		(property "Reference" "C357"
			(at 0 0 90)
			(layer "B.SilkS")
			(hide yes)
			(effects
				(font
					(size 1.27 1.27)
				)
				(justify mirror)
			)
		)
		(property "Value" ""
			(at 0 0 90)
			(layer "B.Fab")
			(effects
				(font
					(size 1.27 1.27)
				)
				(justify mirror)
			)
		)
		(duplicate_pad_numbers_are_jumpers no)
		(fp_line
			(start -1.524 0.762)
			(end 1.524 0.762)
			(stroke
				(width 0.1524)
				(type default)
			)
			(layer "B.SilkS")
		)
		(fp_line
			(start 1.524 0.762)
			(end 1.524 -0.762)
			(stroke
				(width 0.1524)
				(type default)
			)
			(layer "B.SilkS")
		)
		(fp_line
			(start -1.524 -0.762)
			(end -1.524 0.762)
			(stroke
				(width 0.1524)
				(type default)
			)
			(layer "B.SilkS")
		)
		(fp_line
			(start 1.524 -0.762)
			(end -1.524 -0.762)
			(stroke
				(width 0.1524)
				(type default)
			)
			(layer "B.SilkS")
		)
		(fp_line
			(start -1.1049 0.724916)
			(end -1.1049 -0.724916)
			(stroke
				(width 0.1)
				(type default)
			)
			(layer "B.Fab")
		)
		(fp_line
			(start 1.1049 0.724916)
			(end -1.1049 0.724916)
			(stroke
				(width 0.1)
				(type default)
			)
			(layer "B.Fab")
		)
		(fp_line
			(start -1.1049 -0.724916)
			(end 1.1049 -0.724916)
			(stroke
				(width 0.1)
				(type default)
			)
			(layer "B.Fab")
		)
		(fp_line
			(start 1.1049 -0.724916)
			(end 1.1049 0.724916)
			(stroke
				(width 0.1)
				(type default)
			)
			(layer "B.Fab")
		)
		(pad "1" smd rect
			(at 0.889 0 270)
			(size 1.016 1.27)
			(layers "B.Cu" "B.Mask" "B.Paste")
			(net "PVCCIN_CPU0")
		)
		(pad "2" smd rect
			(at -0.889 0 270)
			(size 1.016 1.27)
			(layers "B.Cu" "B.Mask" "B.Paste")
			(net "GND")
		)
	)
)
